# T6G (Grand Teton) — schematic netlist excerpt (pin names and nets, part order shuffled) for the footprints in the layout excerpt that follows; sources: Cadence DE-HDL packaged netlist, KiCad conversion of 04192023_DAF0TMB3IC0_F0TG_MB_C_brd_V02_OCP.brd

PC6505  Q_CAP  1UF 25V 10% X6S  pkg C0402  page 360 : A = SW_P12V_AUX_P1V8_RETIMER_CPU0_FLT ; B = GND
PR8092  Q_RES  86.6K 1% CHIP  pkg 0402LF  page 189 : A = P5V_AUX_FB ; B = P5V_AUX

(kicad_pcb
	(version 20260206)
	(generator "pcbnew")
	(generator_version "10.0")
	(general
		(thickness 1.6)
		(legacy_teardrops no)
	)
	(paper "A4")
	(title_block
		(title "04192023_DAF0TMB3IC0_F0TG_MB_C_brd_V02_OCP.brd")
		(comment 1 "Grand Teton / footprints 2637-2638 of 8354")
	)
	(layers
		(0 "F.Cu" signal "TOP")
		(4 "In1.Cu" signal "GND")
		(6 "In2.Cu" signal "IN1")
		(8 "In3.Cu" signal "GND1")
		(10 "In4.Cu" signal "IN2")
		(12 "In5.Cu" signal "GND2")
		(14 "In6.Cu" signal "IN3")
		(16 "In7.Cu" signal "GND3")
		(18 "In8.Cu" signal "VCC")
		(20 "In9.Cu" signal "VCC1")
		(22 "In10.Cu" signal "GND4")
		(24 "In11.Cu" signal "IN4")
		(26 "In12.Cu" signal "GND5")
		(28 "In13.Cu" signal "IN5")
		(30 "In14.Cu" signal "GND6")
		(32 "In15.Cu" signal "IN6")
		(34 "In16.Cu" signal "GND7")
		(2 "B.Cu" signal "BOTTOM")
		(9 "F.Adhes" user "F.Adhesive")
		(11 "B.Adhes" user "B.Adhesive")
		(13 "F.Paste" user "Package Geometry/Pastemask Top")
		(15 "B.Paste" user "Package Geometry/Pastemask Bottom")
		(5 "F.SilkS" user "Ref Des/Silkscreen Top")
		(7 "B.SilkS" user "Ref Des/Silkscreen Bottom")
		(1 "F.Mask" user "Board Geometry/Soldermask Top")
		(3 "B.Mask" user "Board Geometry/Soldermask Bottom")
		(17 "Dwgs.User" user "User.Drawings")
		(19 "Cmts.User" user "User.Comments")
		(21 "Eco1.User" user "User.Eco1")
		(23 "Eco2.User" user "User.Eco2")
		(25 "Edge.Cuts" user "Board Geometry/Outline")
		(27 "Margin" user)
		(31 "F.CrtYd" user "Package Geometry/Place Bound Top")
		(29 "B.CrtYd" user "Package Geometry/Place Bound Bottom")
		(35 "F.Fab" user "Ref Des/Assembly Top")
		(33 "B.Fab" user "Ref Des/Assembly Bottom")
	)
	(footprint ""
		(layer "F.Cu")
		(at 242.588542 -294.936926 180)
		(property "Reference" "PC6505"
			(at 0 0 180)
			(layer "F.SilkS")
			(hide yes)
			(effects
				(font
					(size 1.27 1.27)
				)
			)
		)
		(property "Value" ""
			(at 0 0 180)
			(layer "F.Fab")
			(effects
				(font
					(size 1.27 1.27)
				)
			)
		)
		(duplicate_pad_numbers_are_jumpers no)
		(fp_line
			(start 0.7874 0.4064)
			(end -0.7874 0.4064)
			(stroke
				(width 0.1524)
				(type default)
			)
			(layer "F.SilkS")
		)
		(fp_line
			(start 0.7874 -0.4064)
			(end 0.7874 0.4064)
			(stroke
				(width 0.1524)
				(type default)
			)
			(layer "F.SilkS")
		)
		(fp_line
			(start -0.7874 0.4064)
			(end -0.7874 -0.4064)
			(stroke
				(width 0.1524)
				(type default)
			)
			(layer "F.SilkS")
		)
		(fp_line
			(start -0.7874 -0.4064)
			(end 0.7874 -0.4064)
			(stroke
				(width 0.1524)
				(type default)
			)
			(layer "F.SilkS")
		)
		(fp_line
			(start 0.67945 0.3048)
			(end 0.120396 0.3048)
			(stroke
				(width 0.1)
				(type default)
			)
			(layer "F.Fab")
		)
		(fp_line
			(start 0.67945 -0.3048)
			(end 0.67945 0.3048)
			(stroke
				(width 0.1)
				(type default)
			)
			(layer "F.Fab")
		)
		(fp_line
			(start 0.12065 -0.2794)
			(end 0.12065 -0.3048)
			(stroke
				(width 0.1)
				(type default)
			)
			(layer "F.Fab")
		)
		(fp_line
			(start 0.12065 -0.3048)
			(end 0.67945 -0.3048)
			(stroke
				(width 0.1)
				(type default)
			)
			(layer "F.Fab")
		)
		(fp_line
			(start 0.120396 0.3048)
			(end 0.120396 0.2794)
			(stroke
				(width 0.1)
				(type default)
			)
			(layer "F.Fab")
		)
		(fp_line
			(start 0.120396 0.2794)
			(end -0.12065 0.2794)
			(stroke
				(width 0.1)
				(type default)
			)
			(layer "F.Fab")
		)
		(fp_line
			(start -0.12065 0.3048)
			(end -0.67945 0.3048)
			(stroke
				(width 0.1)
				(type default)
			)
			(layer "F.Fab")
		)
		(fp_line
			(start -0.12065 0.2794)
			(end -0.12065 0.3048)
			(stroke
				(width 0.1)
				(type default)
			)
			(layer "F.Fab")
		)
		(fp_line
			(start -0.12065 -0.2794)
			(end 0.12065 -0.2794)
			(stroke
				(width 0.1)
				(type default)
			)
			(layer "F.Fab")
		)
		(fp_line
			(start -0.12065 -0.305054)
			(end -0.12065 -0.2794)
			(stroke
				(width 0.1)
				(type default)
			)
			(layer "F.Fab")
		)
		(fp_line
			(start -0.67945 0.3048)
			(end -0.67945 -0.305054)
			(stroke
				(width 0.1)
				(type default)
			)
			(layer "F.Fab")
		)
		(fp_line
			(start -0.67945 -0.305054)
			(end -0.12065 -0.305054)
			(stroke
				(width 0.1)
				(type default)
			)
			(layer "F.Fab")
		)
		(pad "1" smd circle
			(at -0.40005 0 180)
			(size 0 0)
			(layers "F.Cu" "F.Mask" "F.Paste")
			(net "SW_P12V_AUX_P1V8_RETIMER_CPU0_FLT")
		)
		(pad "2" smd circle
			(at 0.40005 0 180)
			(size 0 0)
			(layers "F.Cu" "F.Mask" "F.Paste")
			(net "GND")
		)
	)
	(footprint ""
		(layer "F.Cu")
		(at 408.758644 -139.362942 -90)
		(property "Reference" "PR8092"
			(at 0 0 270)
			(layer "F.SilkS")
			(hide yes)
			(effects
				(font
					(size 1.27 1.27)
				)
			)
		)
		(property "Value" ""
			(at 0 0 270)
			(layer "F.Fab")
			(effects
				(font
					(size 1.27 1.27)
				)
			)
		)
		(duplicate_pad_numbers_are_jumpers no)
		(fp_line
			(start -0.7874 0.4064)
			(end -0.7874 -0.4064)
			(stroke
				(width 0.1524)
				(type default)
			)
			(layer "F.SilkS")
		)
		(fp_line
			(start 0.7874 0.4064)
			(end -0.7874 0.4064)
			(stroke
				(width 0.1524)
				(type default)
			)
			(layer "F.SilkS")
		)
		(fp_line
			(start -0.7874 -0.4064)
			(end 0.7874 -0.4064)
			(stroke
				(width 0.1524)
				(type default)
			)
			(layer "F.SilkS")
		)
		(fp_line
			(start 0.7874 -0.4064)
			(end 0.7874 0.4064)
			(stroke
				(width 0.1524)
				(type default)
			)
			(layer "F.SilkS")
		)
		(fp_line
			(start -0.67945 0.3048)
			(end -0.67945 -0.305054)
			(stroke
				(width 0.1)
				(type default)
			)
			(layer "F.Fab")
		)
		(fp_line
			(start -0.12065 0.3048)
			(end -0.67945 0.3048)
			(stroke
				(width 0.1)
				(type default)
			)
			(layer "F.Fab")
		)
		(fp_line
			(start 0.120396 0.3048)
			(end 0.120396 0.2794)
			(stroke
				(width 0.1)
				(type default)
			)
			(layer "F.Fab")
		)
		(fp_line
			(start 0.67945 0.3048)
			(end 0.120396 0.3048)
			(stroke
				(width 0.1)
				(type default)
			)
			(layer "F.Fab")
		)
		(fp_line
			(start -0.12065 0.2794)
			(end -0.12065 0.3048)
			(stroke
				(width 0.1)
				(type default)
			)
			(layer "F.Fab")
		)
		(fp_line
			(start 0.120396 0.2794)
			(end -0.12065 0.2794)
			(stroke
				(width 0.1)
				(type default)
			)
			(layer "F.Fab")
		)
		(fp_line
			(start -0.12065 -0.2794)
			(end 0.12065 -0.2794)
			(stroke
				(width 0.1)
				(type default)
			)
			(layer "F.Fab")
		)
		(fp_line
			(start 0.12065 -0.2794)
			(end 0.12065 -0.3048)
			(stroke
				(width 0.1)
				(type default)
			)
			(layer "F.Fab")
		)
		(fp_line
			(start 0.12065 -0.3048)
			(end 0.67945 -0.3048)
			(stroke
				(width 0.1)
				(type default)
			)
			(layer "F.Fab")
		)
		(fp_line
			(start 0.67945 -0.3048)
			(end 0.67945 0.3048)
			(stroke
				(width 0.1)
				(type default)
			)
			(layer "F.Fab")
		)
		(fp_line
			(start -0.67945 -0.305054)
			(end -0.12065 -0.305054)
			(stroke
				(width 0.1)
				(type default)
			)
			(layer "F.Fab")
		)
		(fp_line
			(start -0.12065 -0.305054)
			(end -0.12065 -0.2794)
			(stroke
				(width 0.1)
				(type default)
			)
			(layer "F.Fab")
		)
		(pad "1" smd circle
			(at -0.40005 0 270)
			(size 0 0)
			(layers "F.Cu" "F.Mask" "F.Paste")
			(net "P5V_AUX_FB")
		)
		(pad "2" smd circle
			(at 0.40005 0 270)
			(size 0 0)
			(layers "F.Cu" "F.Mask" "F.Paste")
			(net "P5V_AUX")
		)
	)
)
